# S9S_MB_2U (Grand Teton) — schematic netlist excerpt (pin names and nets, part order shuffled) for the footprints in the layout excerpt that follows; sources: Cadence DE-HDL packaged netlist, KiCad conversion of 03242023_DA0F0TMBIJ0_F0T_Motherboard_J_brd_V01_OCP.brd

C521  Q_CAP  47UF 4V 20% X6S  pkg C0805  page 76 : A = PVCCFA_EHV_FIVRA_CPU0 ; B = GND
C1138  Q_CAP  0.01UF 50V 10% X7R  pkg C0402  page 217 : A = P3V3_AUX_FPGA_VCCIO2 ; B = GND
C538  Q_CAP  0.1UF 25V 10% X7R  pkg 0402  page 229 : A = P3V3_AUX ; B = GND

(kicad_pcb
	(version 20260206)
	(generator "pcbnew")
	(generator_version "10.0")
	(general
		(thickness 1.6)
		(legacy_teardrops no)
	)
	(paper "A4")
	(title_block
		(title "03242023_DA0F0TMBIJ0_F0T_Motherboard_J_brd_V01_OCP.brd")
		(comment 1 "Grand Teton / footprints 5961-5963 of 6105")
	)
	(layers
		(0 "F.Cu" signal "TOP")
		(4 "In1.Cu" signal "GND")
		(6 "In2.Cu" signal "IN1")
		(8 "In3.Cu" signal "GND1")
		(10 "In4.Cu" signal "IN2")
		(12 "In5.Cu" signal "GND2")
		(14 "In6.Cu" signal "IN3")
		(16 "In7.Cu" signal "GND3")
		(18 "In8.Cu" signal "VCC")
		(20 "In9.Cu" signal "VCC1")
		(22 "In10.Cu" signal "GND4")
		(24 "In11.Cu" signal "IN4")
		(26 "In12.Cu" signal "GND5")
		(28 "In13.Cu" signal "IN5")
		(30 "In14.Cu" signal "GND6")
		(32 "In15.Cu" signal "IN6")
		(34 "In16.Cu" signal "GND7")
		(2 "B.Cu" signal "BOTTOM")
		(9 "F.Adhes" user "F.Adhesive")
		(11 "B.Adhes" user "B.Adhesive")
		(13 "F.Paste" user "Package Geometry/Pastemask Top")
		(15 "B.Paste" user "Package Geometry/Pastemask Bottom")
		(5 "F.SilkS" user "Ref Des/Silkscreen Top")
		(7 "B.SilkS" user "Ref Des/Silkscreen Bottom")
		(1 "F.Mask" user "Board Geometry/Soldermask Top")
		(3 "B.Mask" user "Board Geometry/Soldermask Bottom")
		(17 "Dwgs.User" user "User.Drawings")
		(19 "Cmts.User" user "User.Comments")
		(21 "Eco1.User" user "User.Eco1")
		(23 "Eco2.User" user "User.Eco2")
		(25 "Edge.Cuts" user "Board Geometry/Outline")
		(27 "Margin" user)
		(31 "F.CrtYd" user "Package Geometry/Place Bound Top")
		(29 "B.CrtYd" user "Package Geometry/Place Bound Bottom")
		(35 "F.Fab" user "Ref Des/Assembly Top")
		(33 "B.Fab" user "Ref Des/Assembly Bottom")
	)
	(footprint ""
		(layer "B.Cu")
		(at 303.472342 -149.533356 180)
		(property "Reference" "C538"
			(at 0 0 0)
			(layer "B.SilkS")
			(hide yes)
			(effects
				(font
					(size 1.27 1.27)
				)
				(justify mirror)
			)
		)
		(property "Value" ""
			(at 0 0 0)
			(layer "B.Fab")
			(effects
				(font
					(size 1.27 1.27)
				)
				(justify mirror)
			)
		)
		(duplicate_pad_numbers_are_jumpers no)
		(fp_line
			(start 0.7874 0.4064)
			(end 0.7874 -0.4064)
			(stroke
				(width 0.1524)
				(type default)
			)
			(layer "B.SilkS")
		)
		(fp_line
			(start 0.7874 -0.4064)
			(end -0.7874 -0.4064)
			(stroke
				(width 0.1524)
				(type default)
			)
			(layer "B.SilkS")
		)
		(fp_line
			(start -0.7874 0.4064)
			(end 0.7874 0.4064)
			(stroke
				(width 0.1524)
				(type default)
			)
			(layer "B.SilkS")
		)
		(fp_line
			(start -0.7874 -0.4064)
			(end -0.7874 0.4064)
			(stroke
				(width 0.1524)
				(type default)
			)
			(layer "B.SilkS")
		)
		(fp_line
			(start 0.67945 0.3048)
			(end 0.67945 -0.305054)
			(stroke
				(width 0.1)
				(type default)
			)
			(layer "B.Fab")
		)
		(fp_line
			(start 0.67945 -0.305054)
			(end 0.12065 -0.305054)
			(stroke
				(width 0.1)
				(type default)
			)
			(layer "B.Fab")
		)
		(fp_line
			(start 0.12065 0.3048)
			(end 0.67945 0.3048)
			(stroke
				(width 0.1)
				(type default)
			)
			(layer "B.Fab")
		)
		(fp_line
			(start 0.12065 0.2794)
			(end 0.12065 0.3048)
			(stroke
				(width 0.1)
				(type default)
			)
			(layer "B.Fab")
		)
		(fp_line
			(start 0.12065 -0.2794)
			(end -0.12065 -0.2794)
			(stroke
				(width 0.1)
				(type default)
			)
			(layer "B.Fab")
		)
		(fp_line
			(start 0.12065 -0.305054)
			(end 0.12065 -0.2794)
			(stroke
				(width 0.1)
				(type default)
			)
			(layer "B.Fab")
		)
		(fp_line
			(start -0.120396 0.3048)
			(end -0.120396 0.2794)
			(stroke
				(width 0.1)
				(type default)
			)
			(layer "B.Fab")
		)
		(fp_line
			(start -0.120396 0.2794)
			(end 0.12065 0.2794)
			(stroke
				(width 0.1)
				(type default)
			)
			(layer "B.Fab")
		)
		(fp_line
			(start -0.12065 -0.2794)
			(end -0.12065 -0.3048)
			(stroke
				(width 0.1)
				(type default)
			)
			(layer "B.Fab")
		)
		(fp_line
			(start -0.12065 -0.3048)
			(end -0.67945 -0.3048)
			(stroke
				(width 0.1)
				(type default)
			)
			(layer "B.Fab")
		)
		(fp_line
			(start -0.67945 0.3048)
			(end -0.120396 0.3048)
			(stroke
				(width 0.1)
				(type default)
			)
			(layer "B.Fab")
		)
		(fp_line
			(start -0.67945 -0.3048)
			(end -0.67945 0.3048)
			(stroke
				(width 0.1)
				(type default)
			)
			(layer "B.Fab")
		)
		(pad "1" smd circle
			(at 0.40005 0)
			(size 0 0)
			(layers "B.Cu" "B.Mask" "B.Paste")
			(net "P3V3_AUX")
		)
		(pad "2" smd circle
			(at -0.40005 0)
			(size 0 0)
			(layers "B.Cu" "B.Mask" "B.Paste")
			(net "GND")
		)
	)
	(footprint ""
		(layer "B.Cu")
		(at 305.470814 -258.379976 -90)
		(property "Reference" "C521"
			(at 0 0 90)
			(layer "B.SilkS")
			(hide yes)
			(effects
				(font
					(size 1.27 1.27)
				)
				(justify mirror)
			)
		)
		(property "Value" ""
			(at 0 0 90)
			(layer "B.Fab")
			(effects
				(font
					(size 1.27 1.27)
				)
				(justify mirror)
			)
		)
		(duplicate_pad_numbers_are_jumpers no)
		(fp_line
			(start -1.524 0.762)
			(end 1.524 0.762)
			(stroke
				(width 0.1524)
				(type default)
			)
			(layer "B.SilkS")
		)
		(fp_line
			(start 1.524 0.762)
			(end 1.524 -0.762)
			(stroke
				(width 0.1524)
				(type default)
			)
			(layer "B.SilkS")
		)
		(fp_line
			(start -1.524 -0.762)
			(end -1.524 0.762)
			(stroke
				(width 0.1524)
				(type default)
			)
			(layer "B.SilkS")
		)
		(fp_line
			(start 1.524 -0.762)
			(end -1.524 -0.762)
			(stroke
				(width 0.1524)
				(type default)
			)
			(layer "B.SilkS")
		)
		(fp_line
			(start -1.1049 0.724916)
			(end -1.1049 -0.724916)
			(stroke
				(width 0.1)
				(type default)
			)
			(layer "B.Fab")
		)
		(fp_line
			(start 1.1049 0.724916)
			(end -1.1049 0.724916)
			(stroke
				(width 0.1)
				(type default)
			)
			(layer "B.Fab")
		)
		(fp_line
			(start -1.1049 -0.724916)
			(end 1.1049 -0.724916)
			(stroke
				(width 0.1)
				(type default)
			)
			(layer "B.Fab")
		)
		(fp_line
			(start 1.1049 -0.724916)
			(end 1.1049 0.724916)
			(stroke
				(width 0.1)
				(type default)
			)
			(layer "B.Fab")
		)
		(pad "1" smd rect
			(at 0.889 0 270)
			(size 1.016 1.27)
			(layers "B.Cu" "B.Mask" "B.Paste")
			(net "PVCCFA_EHV_FIVRA_CPU0")
		)
		(pad "2" smd rect
			(at -0.889 0 270)
			(size 1.016 1.27)
			(layers "B.Cu" "B.Mask" "B.Paste")
			(net "GND")
		)
	)
	(footprint ""
		(layer "B.Cu")
		(at 181.755542 -111.375444)
		(property "Reference" "C1138"
			(at 0 0 0)
			(layer "B.SilkS")
			(hide yes)
			(effects
				(font
					(size 1.27 1.27)
				)
				(justify mirror)
			)
		)
		(property "Value" ""
			(at 0 0 0)
			(layer "B.Fab")
			(effects
				(font
					(size 1.27 1.27)
				)
				(justify mirror)
			)
		)
		(duplicate_pad_numbers_are_jumpers no)
		(fp_line
			(start -0.69215 -0.2921)
			(end -0.69215 0.2921)
			(stroke
				(width 0.1524)
				(type default)
			)
			(layer "B.SilkS")
		)
		(fp_line
			(start -0.69215 0.2921)
			(end 0.69215 0.2921)
			(stroke
				(width 0.1524)
				(type default)
			)
			(layer "B.SilkS")
		)
		(fp_line
			(start 0.69215 -0.2921)
			(end -0.69215 -0.2921)
			(stroke
				(width 0.1524)
				(type default)
			)
			(layer "B.SilkS")
		)
		(fp_line
			(start 0.69215 0.2921)
			(end 0.69215 -0.2921)
			(stroke
				(width 0.1524)
				(type default)
			)
			(layer "B.SilkS")
		)
		(fp_line
			(start -0.51435 -0.2794)
			(end -0.51435 0.2794)
			(stroke
				(width 0.1)
				(type default)
			)
			(layer "B.Fab")
		)
		(fp_line
			(start -0.51435 0.2794)
			(end 0.51435 0.2794)
			(stroke
				(width 0.1)
				(type default)
			)
			(layer "B.Fab")
		)
		(fp_line
			(start 0.51435 -0.2794)
			(end -0.51435 -0.2794)
			(stroke
				(width 0.1)
				(type default)
			)
			(layer "B.Fab")
		)
		(fp_line
			(start 0.51435 0.2794)
			(end 0.51435 -0.2794)
			(stroke
				(width 0.1)
				(type default)
			)
			(layer "B.Fab")
		)
		(pad "1" smd circle
			(at 0.40005 0 180)
			(size 0 0)
			(layers "B.Cu" "B.Mask" "B.Paste")
			(net "P3V3_AUX_FPGA_VCCIO2")
		)
		(pad "2" smd circle
			(at -0.40005 0 180)
			(size 0 0)
			(layers "B.Cu" "B.Mask" "B.Paste")
			(net "GND")
		)
		(zone
			(layer "B.Cu")
			(hatch none 0.5)
			(connect_pads
				(clearance 0)
			)
			(min_thickness 0.25)
			(keepout
				(tracks not_allowed)
				(vias allowed)
				(pads allowed)
				(copperpour not_allowed)
				(footprints allowed)
			)
			(placement
				(enabled no)
				(sheetname "")
			)
			(fill
				(thermal_gap 0.5)
				(thermal_bridge_width 0.5)
				(island_removal_mode 0)
			)
			(polygon
				(pts
					(xy 181.946042 -111.287814) (xy 181.854602 -111.229648) (xy 181.655212 -111.229648) (xy 181.565042 -111.287814)
					(xy 181.565042 -111.463074) (xy 181.655212 -111.521494) (xy 181.854602 -111.521494) (xy 181.946042 -111.463328)
				)
			)
		)
	)
)
